(kicad_pcb
	(version 20260206)
	(generator "pcbnew")
	(generator_version "10.0")
	(general
		(thickness 1.6)
		(legacy_teardrops no)
	)
	(paper "A4")
	(title_block
		(title "04192023_DAF0TMB3IC0_F0TG_MB_C_brd_V02_OCP.brd")
		(comment 1 "Grand Teton / footprints 3198-3204 of 8354")
	)
	(layers
		(0 "F.Cu" signal "TOP")
		(4 "In1.Cu" signal "GND")
		(6 "In2.Cu" signal "IN1")
		(8 "In3.Cu" signal "GND1")
		(10 "In4.Cu" signal "IN2")
		(12 "In5.Cu" signal "GND2")
		(14 "In6.Cu" signal "IN3")
		(16 "In7.Cu" signal "GND3")
		(18 "In8.Cu" signal "VCC")
		(20 "In9.Cu" signal "VCC1")
		(22 "In10.Cu" signal "GND4")
		(24 "In11.Cu" signal "IN4")
		(26 "In12.Cu" signal "GND5")
		(28 "In13.Cu" signal "IN5")
		(30 "In14.Cu" signal "GND6")
		(32 "In15.Cu" signal "IN6")
		(34 "In16.Cu" signal "GND7")
		(2 "B.Cu" signal "BOTTOM")
		(9 "F.Adhes" user "F.Adhesive")
		(11 "B.Adhes" user "B.Adhesive")
		(13 "F.Paste" user "Package Geometry/Pastemask Top")
		(15 "B.Paste" user "Package Geometry/Pastemask Bottom")
		(5 "F.SilkS" user "Ref Des/Silkscreen Top")
		(7 "B.SilkS" user "Ref Des/Silkscreen Bottom")
		(1 "F.Mask" user "Board Geometry/Soldermask Top")
		(3 "B.Mask" user "Board Geometry/Soldermask Bottom")
		(17 "Dwgs.User" user "User.Drawings")
		(19 "Cmts.User" user "User.Comments")
		(21 "Eco1.User" user "User.Eco1")
		(23 "Eco2.User" user "User.Eco2")
		(25 "Edge.Cuts" user "Board Geometry/Outline")
		(27 "Margin" user)
		(31 "F.CrtYd" user "Package Geometry/Place Bound Top")
		(29 "B.CrtYd" user "Package Geometry/Place Bound Bottom")
		(35 "F.Fab" user "Ref Des/Assembly Top")
		(33 "B.Fab" user "Ref Des/Assembly Bottom")
	)
	(footprint ""
		(layer "F.Cu")
		(at 279.022556 -436.223664 90)
		(property "Reference" "R4554"
			(at 0 0 90)
			(layer "F.SilkS")
			(hide yes)
			(effects
				(font
					(size 1.27 1.27)
				)
			)
		)
		(property "Value" ""
			(at 0 0 90)
			(layer "F.Fab")
			(effects
				(font
					(size 1.27 1.27)
				)
			)
		)
		(duplicate_pad_numbers_are_jumpers no)
		(fp_line
			(start 0.7874 -0.4064)
			(end 0.7874 0.4064)
			(stroke
				(width 0.1524)
				(type default)
			)
			(layer "F.SilkS")
		)
		(fp_line
			(start -0.7874 -0.4064)
			(end 0.7874 -0.4064)
			(stroke
				(width 0.1524)
				(type default)
			)
			(layer "F.SilkS")
		)
		(fp_line
			(start 0.7874 0.4064)
			(end -0.7874 0.4064)
			(stroke
				(width 0.1524)
				(type default)
			)
			(layer "F.SilkS")
		)
		(fp_line
			(start -0.7874 0.4064)
			(end -0.7874 -0.4064)
			(stroke
				(width 0.1524)
				(type default)
			)
			(layer "F.SilkS")
		)
		(fp_line
			(start -0.12065 -0.305054)
			(end -0.12065 -0.2794)
			(stroke
				(width 0.1)
				(type default)
			)
			(layer "F.Fab")
		)
		(fp_line
			(start -0.67945 -0.305054)
			(end -0.12065 -0.305054)
			(stroke
				(width 0.1)
				(type default)
			)
			(layer "F.Fab")
		)
		(fp_line
			(start 0.67945 -0.3048)
			(end 0.67945 0.3048)
			(stroke
				(width 0.1)
				(type default)
			)
			(layer "F.Fab")
		)
		(fp_line
			(start 0.12065 -0.3048)
			(end 0.67945 -0.3048)
			(stroke
				(width 0.1)
				(type default)
			)
			(layer "F.Fab")
		)
		(fp_line
			(start 0.12065 -0.2794)
			(end 0.12065 -0.3048)
			(stroke
				(width 0.1)
				(type default)
			)
			(layer "F.Fab")
		)
		(fp_line
			(start -0.12065 -0.2794)
			(end 0.12065 -0.2794)
			(stroke
				(width 0.1)
				(type default)
			)
			(layer "F.Fab")
		)
		(fp_line
			(start 0.120396 0.2794)
			(end -0.12065 0.2794)
			(stroke
				(width 0.1)
				(type default)
			)
			(layer "F.Fab")
		)
		(fp_line
			(start -0.12065 0.2794)
			(end -0.12065 0.3048)
			(stroke
				(width 0.1)
				(type default)
			)
			(layer "F.Fab")
		)
		(fp_line
			(start 0.67945 0.3048)
			(end 0.120396 0.3048)
			(stroke
				(width 0.1)
				(type default)
			)
			(layer "F.Fab")
		)
		(fp_line
			(start 0.120396 0.3048)
			(end 0.120396 0.2794)
			(stroke
				(width 0.1)
				(type default)
			)
			(layer "F.Fab")
		)
		(fp_line
			(start -0.12065 0.3048)
			(end -0.67945 0.3048)
			(stroke
				(width 0.1)
				(type default)
			)
			(layer "F.Fab")
		)
		(fp_line
			(start -0.67945 0.3048)
			(end -0.67945 -0.305054)
			(stroke
				(width 0.1)
				(type default)
			)
			(layer "F.Fab")
		)
		(pad "1" smd circle
			(at -0.40005 0 90)
			(size 0 0)
			(layers "F.Cu" "F.Mask" "F.Paste")
			(net "P3V3_AUX")
		)
		(pad "2" smd circle
			(at 0.40005 0 90)
			(size 0 0)
			(layers "F.Cu" "F.Mask" "F.Paste")
			(net "HPDB_HSC_PWRGD_ISO")
		)
	)
	(footprint ""
		(layer "F.Cu")
		(at 166.624 -129.921 -90)
		(property "Reference" "R494"
			(at 0 0 270)
			(layer "F.SilkS")
			(hide yes)
			(effects
				(font
					(size 1.27 1.27)
				)
			)
		)
		(property "Value" ""
			(at 0 0 270)
			(layer "F.Fab")
			(effects
				(font
					(size 1.27 1.27)
				)
			)
		)
		(duplicate_pad_numbers_are_jumpers no)
		(fp_line
			(start -0.7874 0.4064)
			(end -0.7874 -0.4064)
			(stroke
				(width 0.1524)
				(type default)
			)
			(layer "F.SilkS")
		)
		(fp_line
			(start 0.7874 0.4064)
			(end -0.7874 0.4064)
			(stroke
				(width 0.1524)
				(type default)
			)
			(layer "F.SilkS")
		)
		(fp_line
			(start -0.7874 -0.4064)
			(end 0.7874 -0.4064)
			(stroke
				(width 0.1524)
				(type default)
			)
			(layer "F.SilkS")
		)
		(fp_line
			(start 0.7874 -0.4064)
			(end 0.7874 0.4064)
			(stroke
				(width 0.1524)
				(type default)
			)
			(layer "F.SilkS")
		)
		(fp_line
			(start -0.67945 0.3048)
			(end -0.67945 -0.305054)
			(stroke
				(width 0.1)
				(type default)
			)
			(layer "F.Fab")
		)
		(fp_line
			(start -0.12065 0.3048)
			(end -0.67945 0.3048)
			(stroke
				(width 0.1)
				(type default)
			)
			(layer "F.Fab")
		)
		(fp_line
			(start 0.120396 0.3048)
			(end 0.120396 0.2794)
			(stroke
				(width 0.1)
				(type default)
			)
			(layer "F.Fab")
		)
		(fp_line
			(start 0.67945 0.3048)
			(end 0.120396 0.3048)
			(stroke
				(width 0.1)
				(type default)
			)
			(layer "F.Fab")
		)
		(fp_line
			(start -0.12065 0.2794)
			(end -0.12065 0.3048)
			(stroke
				(width 0.1)
				(type default)
			)
			(layer "F.Fab")
		)
		(fp_line
			(start 0.120396 0.2794)
			(end -0.12065 0.2794)
			(stroke
				(width 0.1)
				(type default)
			)
			(layer "F.Fab")
		)
		(fp_line
			(start -0.12065 -0.2794)
			(end 0.12065 -0.2794)
			(stroke
				(width 0.1)
				(type default)
			)
			(layer "F.Fab")
		)
		(fp_line
			(start 0.12065 -0.2794)
			(end 0.12065 -0.3048)
			(stroke
				(width 0.1)
				(type default)
			)
			(layer "F.Fab")
		)
		(fp_line
			(start 0.12065 -0.3048)
			(end 0.67945 -0.3048)
			(stroke
				(width 0.1)
				(type default)
			)
			(layer "F.Fab")
		)
		(fp_line
			(start 0.67945 -0.3048)
			(end 0.67945 0.3048)
			(stroke
				(width 0.1)
				(type default)
			)
			(layer "F.Fab")
		)
		(fp_line
			(start -0.67945 -0.305054)
			(end -0.12065 -0.305054)
			(stroke
				(width 0.1)
				(type default)
			)
			(layer "F.Fab")
		)
		(fp_line
			(start -0.12065 -0.305054)
			(end -0.12065 -0.2794)
			(stroke
				(width 0.1)
				(type default)
			)
			(layer "F.Fab")
		)
		(pad "1" smd circle
			(at -0.40005 0 270)
			(size 0 0)
			(layers "F.Cu" "F.Mask" "F.Paste")
			(net "PWRGD_P5V_R_N")
		)
		(pad "2" smd circle
			(at 0.40005 0 270)
			(size 0 0)
			(layers "F.Cu" "F.Mask" "F.Paste")
			(net "PWRGD_P5V_N")
		)
	)
	(footprint ""
		(layer "F.Cu")
		(at 156.231844 -373.03583 -90)
		(property "Reference" "C757"
			(at 0 0 270)
			(layer "F.SilkS")
			(hide yes)
			(effects
				(font
					(size 1.27 1.27)
				)
			)
		)
		(property "Value" ""
			(at 0 0 270)
			(layer "F.Fab")
			(effects
				(font
					(size 1.27 1.27)
				)
			)
		)
		(duplicate_pad_numbers_are_jumpers no)
		(fp_line
			(start -0.299974 0.150114)
			(end -0.299974 -0.150114)
			(stroke
				(width 0.1)
				(type default)
			)
			(layer "F.Fab")
		)
		(fp_line
			(start 0.299974 0.150114)
			(end -0.299974 0.150114)
			(stroke
				(width 0.1)
				(type default)
			)
			(layer "F.Fab")
		)
		(fp_line
			(start -0.299974 -0.150114)
			(end 0.299974 -0.150114)
			(stroke
				(width 0.1)
				(type default)
			)
			(layer "F.Fab")
		)
		(fp_line
			(start 0.299974 -0.150114)
			(end 0.299974 0.150114)
			(stroke
				(width 0.1)
				(type default)
			)
			(layer "F.Fab")
		)
		(pad "1" smd rect
			(at -0.2667 0 270)
			(size 0.3048 0.381)
			(layers "F.Cu" "F.Mask" "F.Paste")
			(net "P5E_CPU1_P2_TX_C_DP<8>")
		)
		(pad "2" smd rect
			(at 0.2667 0 270)
			(size 0.3048 0.381)
			(layers "F.Cu" "F.Mask" "F.Paste")
			(net "P5E_CPU1_P2_TX_DP<8>")
		)
	)
	(footprint ""
		(layer "F.Cu")
		(at 208.894426 -106.513376)
		(property "Reference" "R6118"
			(at 0 0 0)
			(layer "F.SilkS")
			(hide yes)
			(effects
				(font
					(size 1.27 1.27)
				)
			)
		)
		(property "Value" ""
			(at 0 0 0)
			(layer "F.Fab")
			(effects
				(font
					(size 1.27 1.27)
				)
			)
		)
		(duplicate_pad_numbers_are_jumpers no)
		(fp_line
			(start -0.7874 -0.4064)
			(end 0.7874 -0.4064)
			(stroke
				(width 0.1524)
				(type default)
			)
			(layer "F.SilkS")
		)
		(fp_line
			(start -0.7874 0.4064)
			(end -0.7874 -0.4064)
			(stroke
				(width 0.1524)
				(type default)
			)
			(layer "F.SilkS")
		)
		(fp_line
			(start 0.7874 -0.4064)
			(end 0.7874 0.4064)
			(stroke
				(width 0.1524)
				(type default)
			)
			(layer "F.SilkS")
		)
		(fp_line
			(start 0.7874 0.4064)
			(end -0.7874 0.4064)
			(stroke
				(width 0.1524)
				(type default)
			)
			(layer "F.SilkS")
		)
		(fp_line
			(start -0.67945 -0.305054)
			(end -0.12065 -0.305054)
			(stroke
				(width 0.1)
				(type default)
			)
			(layer "F.Fab")
		)
		(fp_line
			(start -0.67945 0.3048)
			(end -0.67945 -0.305054)
			(stroke
				(width 0.1)
				(type default)
			)
			(layer "F.Fab")
		)
		(fp_line
			(start -0.12065 -0.305054)
			(end -0.12065 -0.2794)
			(stroke
				(width 0.1)
				(type default)
			)
			(layer "F.Fab")
		)
		(fp_line
			(start -0.12065 -0.2794)
			(end 0.12065 -0.2794)
			(stroke
				(width 0.1)
				(type default)
			)
			(layer "F.Fab")
		)
		(fp_line
			(start -0.12065 0.2794)
			(end -0.12065 0.3048)
			(stroke
				(width 0.1)
				(type default)
			)
			(layer "F.Fab")
		)
		(fp_line
			(start -0.12065 0.3048)
			(end -0.67945 0.3048)
			(stroke
				(width 0.1)
				(type default)
			)
			(layer "F.Fab")
		)
		(fp_line
			(start 0.120396 0.2794)
			(end -0.12065 0.2794)
			(stroke
				(width 0.1)
				(type default)
			)
			(layer "F.Fab")
		)
		(fp_line
			(start 0.120396 0.3048)
			(end 0.120396 0.2794)
			(stroke
				(width 0.1)
				(type default)
			)
			(layer "F.Fab")
		)
		(fp_line
			(start 0.12065 -0.3048)
			(end 0.67945 -0.3048)
			(stroke
				(width 0.1)
				(type default)
			)
			(layer "F.Fab")
		)
		(fp_line
			(start 0.12065 -0.2794)
			(end 0.12065 -0.3048)
			(stroke
				(width 0.1)
				(type default)
			)
			(layer "F.Fab")
		)
		(fp_line
			(start 0.67945 -0.3048)
			(end 0.67945 0.3048)
			(stroke
				(width 0.1)
				(type default)
			)
			(layer "F.Fab")
		)
		(fp_line
			(start 0.67945 0.3048)
			(end 0.120396 0.3048)
			(stroke
				(width 0.1)
				(type default)
			)
			(layer "F.Fab")
		)
		(pad "1" smd circle
			(at -0.40005 0)
			(size 0 0)
			(layers "F.Cu" "F.Mask" "F.Paste")
			(net "PWRGD_P5V_AUX_R3")
		)
		(pad "2" smd circle
			(at 0.40005 0)
			(size 0 0)
			(layers "F.Cu" "F.Mask" "F.Paste")
			(net "PWRGD_P5V_AUX_R2")
		)
	)
	(footprint ""
		(layer "F.Cu")
		(at 441.179966 -418.961824)
		(property "Reference" "PR6531"
			(at 0 0 0)
			(layer "F.SilkS")
			(hide yes)
			(effects
				(font
					(size 1.27 1.27)
				)
			)
		)
		(property "Value" ""
			(at 0 0 0)
			(layer "F.Fab")
			(effects
				(font
					(size 1.27 1.27)
				)
			)
		)
		(duplicate_pad_numbers_are_jumpers no)
		(fp_line
			(start -0.7874 -0.4064)
			(end 0.7874 -0.4064)
			(stroke
				(width 0.1524)
				(type default)
			)
			(layer "F.SilkS")
		)
		(fp_line
			(start -0.7874 0.4064)
			(end -0.7874 -0.4064)
			(stroke
				(width 0.1524)
				(type default)
			)
			(layer "F.SilkS")
		)
		(fp_line
			(start 0.7874 -0.4064)
			(end 0.7874 0.4064)
			(stroke
				(width 0.1524)
				(type default)
			)
			(layer "F.SilkS")
		)
		(fp_line
			(start 0.7874 0.4064)
			(end -0.7874 0.4064)
			(stroke
				(width 0.1524)
				(type default)
			)
			(layer "F.SilkS")
		)
		(fp_line
			(start -0.67945 -0.305054)
			(end -0.12065 -0.305054)
			(stroke
				(width 0.1)
				(type default)
			)
			(layer "F.Fab")
		)
		(fp_line
			(start -0.67945 0.3048)
			(end -0.67945 -0.305054)
			(stroke
				(width 0.1)
				(type default)
			)
			(layer "F.Fab")
		)
		(fp_line
			(start -0.12065 -0.305054)
			(end -0.12065 -0.2794)
			(stroke
				(width 0.1)
				(type default)
			)
			(layer "F.Fab")
		)
		(fp_line
			(start -0.12065 -0.2794)
			(end 0.12065 -0.2794)
			(stroke
				(width 0.1)
				(type default)
			)
			(layer "F.Fab")
		)
		(fp_line
			(start -0.12065 0.2794)
			(end -0.12065 0.3048)
			(stroke
				(width 0.1)
				(type default)
			)
			(layer "F.Fab")
		)
		(fp_line
			(start -0.12065 0.3048)
			(end -0.67945 0.3048)
			(stroke
				(width 0.1)
				(type default)
			)
			(layer "F.Fab")
		)
		(fp_line
			(start 0.120396 0.2794)
			(end -0.12065 0.2794)
			(stroke
				(width 0.1)
				(type default)
			)
			(layer "F.Fab")
		)
		(fp_line
			(start 0.120396 0.3048)
			(end 0.120396 0.2794)
			(stroke
				(width 0.1)
				(type default)
			)
			(layer "F.Fab")
		)
		(fp_line
			(start 0.12065 -0.3048)
			(end 0.67945 -0.3048)
			(stroke
				(width 0.1)
				(type default)
			)
			(layer "F.Fab")
		)
		(fp_line
			(start 0.12065 -0.2794)
			(end 0.12065 -0.3048)
			(stroke
				(width 0.1)
				(type default)
			)
			(layer "F.Fab")
		)
		(fp_line
			(start 0.67945 -0.3048)
			(end 0.67945 0.3048)
			(stroke
				(width 0.1)
				(type default)
			)
			(layer "F.Fab")
		)
		(fp_line
			(start 0.67945 0.3048)
			(end 0.120396 0.3048)
			(stroke
				(width 0.1)
				(type default)
			)
			(layer "F.Fab")
		)
		(pad "1" smd circle
			(at -0.40005 0)
			(size 0 0)
			(layers "F.Cu" "F.Mask" "F.Paste")
			(net "P0V9_RETIMER_CPU0_SENSE_SH_P")
		)
		(pad "2" smd circle
			(at 0.40005 0)
			(size 0 0)
			(layers "F.Cu" "F.Mask" "F.Paste")
			(net "P0V9_RETIMER_CPU0_SENSE_R_P")
		)
	)
	(footprint ""
		(layer "F.Cu")
		(at 421.92194 -109.271308 90)
		(property "Reference" "PC2162"
			(at 0 0 90)
			(layer "F.SilkS")
			(hide yes)
			(effects
				(font
					(size 1.27 1.27)
				)
			)
		)
		(property "Value" ""
			(at 0 0 90)
			(layer "F.Fab")
			(effects
				(font
					(size 1.27 1.27)
				)
			)
		)
		(duplicate_pad_numbers_are_jumpers no)
		(fp_line
			(start 0.7874 -0.4064)
			(end 0.7874 0.4064)
			(stroke
				(width 0.1524)
				(type default)
			)
			(layer "F.SilkS")
		)
		(fp_line
			(start -0.7874 -0.4064)
			(end 0.7874 -0.4064)
			(stroke
				(width 0.1524)
				(type default)
			)
			(layer "F.SilkS")
		)
		(fp_line
			(start 0.7874 0.4064)
			(end -0.7874 0.4064)
			(stroke
				(width 0.1524)
				(type default)
			)
			(layer "F.SilkS")
		)
		(fp_line
			(start -0.7874 0.4064)
			(end -0.7874 -0.4064)
			(stroke
				(width 0.1524)
				(type default)
			)
			(layer "F.SilkS")
		)
		(fp_line
			(start -0.12065 -0.305054)
			(end -0.12065 -0.2794)
			(stroke
				(width 0.1)
				(type default)
			)
			(layer "F.Fab")
		)
		(fp_line
			(start -0.67945 -0.305054)
			(end -0.12065 -0.305054)
			(stroke
				(width 0.1)
				(type default)
			)
			(layer "F.Fab")
		)
		(fp_line
			(start 0.67945 -0.3048)
			(end 0.67945 0.3048)
			(stroke
				(width 0.1)
				(type default)
			)
			(layer "F.Fab")
		)
		(fp_line
			(start 0.12065 -0.3048)
			(end 0.67945 -0.3048)
			(stroke
				(width 0.1)
				(type default)
			)
			(layer "F.Fab")
		)
		(fp_line
			(start 0.12065 -0.2794)
			(end 0.12065 -0.3048)
			(stroke
				(width 0.1)
				(type default)
			)
			(layer "F.Fab")
		)
		(fp_line
			(start -0.12065 -0.2794)
			(end 0.12065 -0.2794)
			(stroke
				(width 0.1)
				(type default)
			)
			(layer "F.Fab")
		)
		(fp_line
			(start 0.120396 0.2794)
			(end -0.12065 0.2794)
			(stroke
				(width 0.1)
				(type default)
			)
			(layer "F.Fab")
		)
		(fp_line
			(start -0.12065 0.2794)
			(end -0.12065 0.3048)
			(stroke
				(width 0.1)
				(type default)
			)
			(layer "F.Fab")
		)
		(fp_line
			(start 0.67945 0.3048)
			(end 0.120396 0.3048)
			(stroke
				(width 0.1)
				(type default)
			)
			(layer "F.Fab")
		)
		(fp_line
			(start 0.120396 0.3048)
			(end 0.120396 0.2794)
			(stroke
				(width 0.1)
				(type default)
			)
			(layer "F.Fab")
		)
		(fp_line
			(start -0.12065 0.3048)
			(end -0.67945 0.3048)
			(stroke
				(width 0.1)
				(type default)
			)
			(layer "F.Fab")
		)
		(fp_line
			(start -0.67945 0.3048)
			(end -0.67945 -0.305054)
			(stroke
				(width 0.1)
				(type default)
			)
			(layer "F.Fab")
		)
		(pad "1" smd circle
			(at -0.40005 0 90)
			(size 0 0)
			(layers "F.Cu" "F.Mask" "F.Paste")
			(net "P3V3_OCP_GATE_1")
		)
		(pad "2" smd circle
			(at 0.40005 0 90)
			(size 0 0)
			(layers "F.Cu" "F.Mask" "F.Paste")
			(net "GND")
		)
	)
	(footprint ""
		(layer "F.Cu")
		(at 298.316142 -404.4188 -90)
		(property "Reference" "L12"
			(at -0.2286 -3.048508 90)
			(unlocked yes)
			(layer "F.SilkS")
			(effects
				(font
					(size 0.7874 0.5842)
					(thickness 0.1524)
				)
				(justify left)
			)
		)
		(property "Value" ""
			(at 0 0 270)
			(layer "F.Fab")
			(effects
				(font
					(size 1.27 1.27)
				)
			)
		)
		(duplicate_pad_numbers_are_jumpers no)
		(fp_line
			(start -2.249932 2.249932)
			(end -2.249932 1.3843)
			(stroke
				(width 0.1524)
				(type default)
			)
			(layer "F.SilkS")
		)
		(fp_line
			(start 2.249932 2.249932)
			(end -2.249932 2.249932)
			(stroke
				(width 0.1524)
				(type default)
			)
			(layer "F.SilkS")
		)
		(fp_line
			(start 2.249932 1.3843)
			(end 2.249932 2.249932)
			(stroke
				(width 0.1524)
				(type default)
			)
			(layer "F.SilkS")
		)
		(fp_line
			(start -2.249932 -1.3843)
			(end -2.249932 -2.249932)
			(stroke
				(width 0.1524)
				(type default)
			)
			(layer "F.SilkS")
		)
		(fp_line
			(start -2.249932 -2.249932)
			(end 2.249932 -2.249932)
			(stroke
				(width 0.1524)
				(type default)
			)
			(layer "F.SilkS")
		)
		(fp_line
			(start 2.249932 -2.249932)
			(end 2.249932 -1.3843)
			(stroke
				(width 0.1524)
				(type default)
			)
			(layer "F.SilkS")
		)
		(fp_line
			(start -2.249932 2.249932)
			(end -2.249932 -2.249932)
			(stroke
				(width 0.1)
				(type default)
			)
			(layer "F.Fab")
		)
		(fp_line
			(start 2.249932 2.249932)
			(end -2.249932 2.249932)
			(stroke
				(width 0.1)
				(type default)
			)
			(layer "F.Fab")
		)
		(fp_line
			(start -2.249932 -2.249932)
			(end 2.249932 -2.249932)
			(stroke
				(width 0.1)
				(type default)
			)
			(layer "F.Fab")
		)
		(fp_line
			(start 2.249932 -2.249932)
			(end 2.249932 2.249932)
			(stroke
				(width 0.1)
				(type default)
			)
			(layer "F.Fab")
		)
		(pad "1" smd rect
			(at -1.82499 0 270)
			(size 1.0668 2.5146)
			(layers "F.Cu" "F.Mask" "F.Paste")
			(net "P0V9_CPU0_RT_2D")
		)
		(pad "2" smd rect
			(at 1.82499 0 270)
			(size 1.0668 2.5146)
			(layers "F.Cu" "F.Mask" "F.Paste")
			(net "P0V9_CPU0_RT0_2A")
		)
	)
)
